FILE_TYPE = CONNECTIVITY;
{Allegro Design Entry HDL 17.2-2016 S081 (4005846) 1/11/2022}
"PAGE_NUMBER" = 312;
0"NC";
1"P3V3_AUX\g";
2"P3V3_AUX\g";
3"P3V3_AUX\g";
4"P3V3_AUX_FPGA_VCCIO2\g";
5"GND\g";
6"GND\g";
7"FM_PLD_HEARTBEAT_LVC3"CDS_PHYS_NET_NAME"FM_PLD_HEARTBEAT_LVC3";
8"FM_DEBUG_PORT_PRSNT_N"CDS_PHYS_NET_NAME"FM_DEBUG_PORT_PRSNT_N";
9"JTAG_DBP_BMC_PRDY_R_N"CDS_PHYS_NET_NAME"JTAG_DBP_BMC_PRDY_R_N";
10"CLK_25M_OSC_MAIN_FPGA"CDS_PHYS_NET_NAME"CLK_25M_OSC_MAIN_FPGA";
11"FM_PCH_BMC_RST_N"CDS_PHYS_NET_NAME"PD_GPP_I_12";
12"HSC_D_OC_R1"CDS_PHYS_NET_NAME"PCIE_M2_SSD0_PRSNT_N";
13"E1S_0_PRSNT_N"CDS_PHYS_NET_NAME"PCIE_M2_SSD0_PRSNT_N";
14"FM_FORCE_PWRON_LVC3"CDS_PHYS_NET_NAME"FM_FORCE_PWRON_LVC3";
15"PRSNT_SWB_ISO_R_N"CDS_PHYS_NET_NAME"BMC_MONITER_R";
16"HSC_D_OC"CDS_PHYS_NET_NAME"BMC_MONITER";
17"GPU_3V3IO_RSVD0_FFU_ISO_R"CDS_PHYS_NET_NAME"CLK_25M_OSC_MAIN_FPGA";
18"FM_DEBUG_PORT_PRSNT_N"CDS_PHYS_NET_NAME"FM_DEBUG_PORT_PRSNT_N";
19"FM_PCH_BMC_RST_N"CDS_PHYS_NET_NAME"PD_GPP_I_12";
20"FM_DEBUG_PORT_PRSNT_R_N"CDS_PHYS_NET_NAME"FM_DEBUG_PORT_PRSNT_R_N";
21"FM_REMOTE_DEBUG_DET"CDS_PHYS_NET_NAME"FM_REMOTE_DEBUG_DET";
22"FM_PCH_BMC_RST_R_N"CDS_PHYS_NET_NAME"PD_GPP_I_12";
23"FM_PDB_BUF_EN";
24"GPU_3V3IO_RSVD4_ISO_R"CDS_PHYS_NET_NAME"CLK_25M_OSC_MAIN_FPGA";
25"IRQ_PCH_SCI_WHEA_R_N"CDS_PHYS_NET_NAME"IRQ_PCH_SCI_WHEA_R_N";
26"IRQ_SML1_PMBUS_ALERT_N"CDS_PHYS_NET_NAME"IRQ_SML1_PMBUS_ALERT_N";
27"PRSNT_CABLE_GPU_B3_ISO_R_N"CDS_PHYS_NET_NAME"CLK_25M_OSC_MAIN_FPGA";
28"SWB_HSC_PWRGD_ISO";
29"SWB_HSC_EN_R"CDS_PHYS_NET_NAME"BMC_MONITER_R";
30"IRQ_UV_DETECT_N";
31"FM_UV_ADR_TRIGGER_N";
32"FM_ADR_ACK_R"CDS_PHYS_NET_NAME"FM_ADR_ACK_R";
33"FM_BMC_READY_R_PLD_N"CDS_PHYS_NET_NAME"FM_BMC_READY_R_PLD_N";
34"FM_REMOTE_DEBUG_DET_R"CDS_PHYS_NET_NAME"FM_REMOTE_DEBUG_DET_R";
35"NC_FPGA_PB32D"CDS_PHYS_NET_NAME"PWRGD_SYS_PWROK_R";
36"FM_BMC_DBP_PRESENT_R_N"CDS_PHYS_NET_NAME"FM_BMC_DBP_PRESENT_R_N";
37"FM_REMOTE_DEBUG_DET"CDS_PHYS_NET_NAME"FM_REMOTE_DEBUG_DET";
38"RST_PLTRST_PLD_B_N"CDS_PHYS_NET_NAME"RST_PLTRST_PLD_B_N";
39"FM_ME_BT_DONE"CDS_PHYS_NET_NAME"FM_ME_BT_DONE";
40"RST_SGPIO_RESET_N_R"CDS_PHYS_NET_NAME"RST_SGPIO_RESET_N_R";
41"IRQ_PSU_ALERT_R_N"CDS_PHYS_NET_NAME"IRQ_PSU_ALERT_R_N";
42"IRQ_PCH_SCI_WHEA_R_N"CDS_PHYS_NET_NAME"IRQ_PCH_SCI_WHEA_R_N";
43"IRQ_TPM_SPI_N"CDS_PHYS_NET_NAME"IRQ_TPM_SPI_N";
44"IRQ_PVCCD_CPU1_VRHOT_LVC3_N"CDS_PHYS_NET_NAME"IRQ_PVCCD_CPU1_VRHOT_LVC3_N";
45"IRQ_PCH_CPU_NMI_EVENT_N"CDS_PHYS_NET_NAME"IRQ_PCH_CPU_NMI_EVENT_N";
46"IRQ_PSYS_CRIT_N"CDS_PHYS_NET_NAME"IRQ_PSYS_CRIT_N";
47"IRQ_SGPIO_INTR_N_R"CDS_PHYS_NET_NAME"IRQ_SGPIO_INTR_N_R";
48"FM_UV_ADR_TRIGGER_R_N"CDS_PHYS_NET_NAME"FM_UV_ADR_TRIGGER_R_N";
49"FM_ADR_ACK_R"CDS_PHYS_NET_NAME"FM_ADR_ACK_R";
50"PU_FORCE_PWRON"CDS_PHYS_NET_NAME"FM_ADR_ACK_R";
51"FM_FORCE_PWRON_LVC3"CDS_PHYS_NET_NAME"FM_FORCE_PWRON_LVC3";
52"FM_PLD_CLK_25M_R_EN"CDS_PHYS_NET_NAME"FM_PLD_CLK_25M_R_EN";
53"PD_FORCE_PWRON"CDS_PHYS_NET_NAME"FM_ADR_ACK_R";
54"RST_PCIE_PCH_DEV_PERST_N"CDS_PHYS_NET_NAME"RST_PCIE_PCH_DEV_PERST_N";
55"VIRTUAL_RESEAT"CDS_PHYS_NET_NAME"VIRTUAL_RESEAT";
56"HPDB_HSC_PWRGD_ISO"CDS_PHYS_NET_NAME"BMC_MONITER";
57"FM_ADR_MODE0_R"CDS_PHYS_NET_NAME"FM_ADR_MODE0_R";
58"PCIE_M2_SSD0_PRSNT_N"CDS_PHYS_NET_NAME"PCIE_M2_SSD0_PRSNT_N";
59"RST_MB_STBY_R_N"CDS_PHYS_NET_NAME"RST_MB_STBY_R_N";
60"FM_PCH_PLD_GLB_RST_WARN_N"CDS_PHYS_NET_NAME"FM_PCH_PLD_GLB_RST_WARN_N";
61"FM_ME_AUTHN_FAIL"CDS_PHYS_NET_NAME"FM_ME_AUTHN_FAIL";
62"RST_PFR_OVR_SRTC_R"CDS_PHYS_NET_NAME"RST_PFR_OVR_SRTC_R";
63"FM_DIS_PS_PWROK_DLY"CDS_PHYS_NET_NAME"FM_DIS_PS_PWROK_DLY";
64"FM_BIOS_POST_CMPLT_BMC_N"CDS_PHYS_NET_NAME"FM_BIOS_POST_CMPLT_BMC_N";
65"FM_PS_PWROK_DLY_SEL"CDS_PHYS_NET_NAME"FM_PS_PWROK_DLY_SEL";
66"FM_RST_PERST_BIT2"CDS_PHYS_NET_NAME"FM_RST_PERST_BIT2";
67"FM_CPU_RMCA_CATERR_LVT3_R_N"CDS_PHYS_NET_NAME"FM_CPU_RMCA_CATERR_LVT3_R_N";
68"FM_PCH_BMC_THERMTRIP_N"CDS_PHYS_NET_NAME"FM_PCH_BMC_THERMTRIP_N";
69"FM_BMC_RSTBTN_OUT_N"CDS_PHYS_NET_NAME"FM_BMC_RSTBTN_OUT_N";
70"FM_PCH_CRASHLOG_TRIG_R_N"CDS_PHYS_NET_NAME"FM_PCH_CRASHLOG_TRIG_R_N";
71"RST_PFR_OVR_RTC_R"CDS_PHYS_NET_NAME"RST_PFR_OVR_RTC_R";
72"RST_SMB_SWITCH_N"CDS_PHYS_NET_NAME"RST_SMB_SWITCH_N";
73"FM_HBM2_HBM3_VPP_SEL"CDS_PHYS_NET_NAME"FM_HBM2_HBM3_VPP_SEL";
74"IRQ_PVCCD_CPU0_VRHOT_LVC3_N"CDS_PHYS_NET_NAME"IRQ_PVCCD_CPU0_VRHOT_LVC3_N";
75"FM_UV_ADR_TRIGGER_R_N"CDS_PHYS_NET_NAME"FM_UV_ADR_TRIGGER_R_N";
76"FM_ADR_TRIGGER_N"CDS_PHYS_NET_NAME"FM_ADR_TRIGGER_N";
77"FM_ADR_COMPLETE"CDS_PHYS_NET_NAME"FM_ADR_COMPLETE";
78"FM_ADR_MODE1_R"CDS_PHYS_NET_NAME"FM_ADR_MODE1_R";
79"IRQ_UV_DETECT_R_N"CDS_PHYS_NET_NAME"IRQ_UV_DETECT_R_N";
80"NC_FPGA_PB7D"CDS_PHYS_NET_NAME"PWRGD_SYS_PWROK_R";
81"IRQ_BMC_PCH_NMI_R"CDS_PHYS_NET_NAME"IRQ_BMC_PCH_NMI_R";
82"FM_PLD_CLKS_DEV_R_EN"CDS_PHYS_NET_NAME"FM_PLD_CLKS_DEV_R_EN";
83"PWRGD_PLT_AUX_CPU0_LVT3_R"CDS_PHYS_NET_NAME"PWRGD_PLT_AUX_CPU0_LVT3_R";
84"PWRGD_PLT_AUX_CPU1_LVT3_R"CDS_PHYS_NET_NAME"PWRGD_PLT_AUX_CPU1_LVT3_R";
85"FM_SYS_THROTTLE_R_N"CDS_PHYS_NET_NAME"FM_SYS_THROTTLE_R_N";
86"FM_NCSI_OCP_V3_1_R_OE"CDS_PHYS_NET_NAME"FM_NCSI_OCP_V3_1_R_OE";
87"FM_BIOS_DEBUG_EN_N"CDS_PHYS_NET_NAME"FM_BIOS_DEBUG_EN_N";
88"IRQ_BMC_CPU_NMI_R1"CDS_PHYS_NET_NAME"IRQ_BMC_CPU_NMI_R1";
89"FM_DIMM_12V_CPS_SX_N"CDS_PHYS_NET_NAME"FM_DIMM_12V_CPS_SX_N";
90"ROT_P1_RST_IND_N_R"CDS_PHYS_NET_NAME"ROT_P1_RST_IND_N_R";
91"FM_PCHHOT_R_N"CDS_PHYS_NET_NAME"FM_PCHHOT_R_N";
92"RST_PLTRST_PLD_N"CDS_PHYS_NET_NAME"RST_PLTRST_PLD_N";
93"FM_SLPS3_PLD_N"CDS_PHYS_NET_NAME"FM_SLPS3_PLD_N";
94"HPDB_HSC_PWRGD_ISO_R"CDS_PHYS_NET_NAME"PWRGD_SYS_PWROK_R";
95"RST_RSMRST_PLD_R_N"CDS_PHYS_NET_NAME"RST_RSMRST_PLD_R_N";
96"IRQ_UV_DETECT_R_N"CDS_PHYS_NET_NAME"IRQ_UV_DETECT_R_N";
97"FM_ADR_ACK"CDS_PHYS_NET_NAME"FM_ADR_ACK";
98"IRQ_PCH_SCI_WHEA_N"CDS_PHYS_NET_NAME"IRQ_PCH_SCI_WHEA_N";
99"IRQ_PSU_ALERT_R_N"CDS_PHYS_NET_NAME"IRQ_PSU_ALERT_R_N";
100"FM_BMC_READY_R_PLD_N"CDS_PHYS_NET_NAME"FM_BMC_READY_R_PLD_N";
101"RST_PCIE_PCH_DEV_PERST_M2_R_N";
102"HGX_DETECT_N_R"CDS_PHYS_NET_NAME"PWRGD_SYS_PWROK_R";
103"SWB_HSC_PWRGD_ISO_R"CDS_PHYS_NET_NAME"BMC_MONITER";
104"FM_THROTTLE_R_N"CDS_PHYS_NET_NAME"FM_THROTTLE_R_N";
105"FM_SPD_REMOTE_EN_R"CDS_PHYS_NET_NAME"FM_SPD_REMOTE_EN_R";
106"NC_FPGA_PB35B"CDS_PHYS_NET_NAME"FM_P12V_HSC_ENABLE";
107"HPDB_HSC_PWRGD_ISO_R"CDS_PHYS_NET_NAME"BMC_MONITER_R";
108"HGX_DETECT_N"CDS_PHYS_NET_NAME"BMC_MONITER_R";
109"RST_PCIE_PCH_DEV_PERST_E1S_R_N"CDS_PHYS_NET_NAME"FM_BMC_READY_R_N";
110"FM_PDB_BUF_EN_R";
111"USB_OC1_REAR_N"CDS_PHYS_NET_NAME"USB_OC1_REAR_N";
112"NC_FPGA_PB46B"CDS_PHYS_NET_NAME"PWRGD_SYS_PWROK_R";
113"SWB_HSC_EN_R"CDS_PHYS_NET_NAME"PWRGD_SYS_PWROK_R";
114"JTAG_DBP_BMC_PREQ_R_N"CDS_PHYS_NET_NAME"JTAG_DBP_BMC_PREQ_R_N";
115"CLK_GPU_1_OE_N";
116"NC_FPGA_PB43D";
117"CLK_SWB_OE_N"CDS_PHYS_NET_NAME"CLK_BB_OE_N";
118"CLK_GPU_2_OE_N";
119"HGX_DETECT_N_R"CDS_PHYS_NET_NAME"BMC_MONITER";
120"CLK_SWB_BUF2_OE_N";
121"CLK_GEN2_BMC_RC_OE_N";
122"FM_PLD_REV_N"CDS_PHYS_NET_NAME"FM_PLD_REV_N";
123"FM_PLD_REV_R_N"CDS_PHYS_NET_NAME"FM_PLD_REV_R_N";
124"FM_BMC_READY_R_N"CDS_PHYS_NET_NAME"FM_BMC_READY_R_N";
125"FM_AC_PWR_BTN_PLD_ISO_N";
126"RST_PCIE_PCH_DEV_PERST_N"CDS_PHYS_NET_NAME"FM_BMC_READY_R_PLD_N";
127"PULL_FPGA_PB46A";
128"FM_PDB_BUF_EN";
129"SWB_HSC_PWRGD_ISO_R"CDS_PHYS_NET_NAME"BMC_MONITER";
130"GPU_3V3IO_RSVD1_FFU_ISO"CDS_PHYS_NET_NAME"CLK_25M_OSC_FPGA_R";
131"GPU_3V3IO_RSVD0_FFU_ISO"CDS_PHYS_NET_NAME"CLK_25M_OSC_FPGA_R";
132"PRSNT_SWB_ISO_N"CDS_PHYS_NET_NAME"BMC_MONITER";
133"GPU_3V3IO_RSVD3_FFU_ISO"CDS_PHYS_NET_NAME"CLK_25M_OSC_FPGA_R";
134"PRSNT_CABLE_GPU_B3_ISO_N"CDS_PHYS_NET_NAME"CLK_25M_OSC_FPGA_R";
135"PRSNT_CABLE_GPU_A2_ISO_N"CDS_PHYS_NET_NAME"CLK_25M_OSC_FPGA_R";
136"GPU_3V3IO_RSVD4_ISO"CDS_PHYS_NET_NAME"CLK_25M_OSC_FPGA_R";
137"GPU_3V3IO_RSVD3_ISO"CDS_PHYS_NET_NAME"CLK_25M_OSC_FPGA_R";
138"GPU_3V3IO_RSVD1_ISO"CDS_PHYS_NET_NAME"CLK_25M_OSC_FPGA_R";
139"GPU_3V3IO_RSVD5_FFU_ISO"CDS_PHYS_NET_NAME"CLK_25M_OSC_FPGA_R";
140"PRSNT_CABLE_GPU_A1_ISO_N"CDS_PHYS_NET_NAME"CLK_25M_OSC_FPGA_R";
141"GPU_3V3IO_RSVD1_FFU_ISO_R"CDS_PHYS_NET_NAME"CLK_25M_OSC_MAIN_FPGA";
142"GPU_3V3IO_RSVD0_FFU_ISO_R"CDS_PHYS_NET_NAME"CLK_25M_OSC_MAIN_FPGA";
143"NC_FPGA_PB22B"CDS_PHYS_NET_NAME"PWRGD_SYS_PWROK_R";
144"GPU_3V3IO_RSVD3_FFU_ISO_R"CDS_PHYS_NET_NAME"CLK_25M_OSC_MAIN_FPGA";
145"PRSNT_CABLE_GPU_A2_ISO_R_N"CDS_PHYS_NET_NAME"CLK_25M_OSC_MAIN_FPGA";
146"GPU_3V3IO_RSVD3_FFU_ISO_R"CDS_PHYS_NET_NAME"CLK_25M_OSC_MAIN_FPGA";
147"PRSNT_CABLE_GPU_B3_ISO_R_N"CDS_PHYS_NET_NAME"CLK_25M_OSC_MAIN_FPGA";
148"PRSNT_SWB_ISO_R_N"CDS_PHYS_NET_NAME"BMC_MONITER_R";
149"HSC_D_OC_R1"CDS_PHYS_NET_NAME"BMC_MONITER_R";
150"SWB_HSC_EN"CDS_PHYS_NET_NAME"BMC_MONITER";
151"GPU_3V3IO_RSVD1_ISO_R"CDS_PHYS_NET_NAME"CLK_25M_OSC_MAIN_FPGA";
152"GPU_3V3IO_RSVD5_FFU_ISO_R"CDS_PHYS_NET_NAME"CLK_25M_OSC_MAIN_FPGA";
153"GPU_3V3IO_RSVD3_ISO_R"CDS_PHYS_NET_NAME"CLK_25M_OSC_MAIN_FPGA";
154"PRSNT_CABLE_GPU_A1_ISO_R_N"CDS_PHYS_NET_NAME"CLK_25M_OSC_MAIN_FPGA";
155"GPU_3V3IO_RSVD4_ISO_R"CDS_PHYS_NET_NAME"CLK_25M_OSC_MAIN_FPGA";
156"GPU_3V3IO_RSVD3_ISO_R"CDS_PHYS_NET_NAME"CLK_25M_OSC_MAIN_FPGA";
157"PRSNT_CABLE_GPU_A2_ISO_R_N"CDS_PHYS_NET_NAME"CLK_25M_OSC_MAIN_FPGA";
158"GPU_3V3IO_RSVD5_FFU_ISO_R"CDS_PHYS_NET_NAME"CLK_25M_OSC_MAIN_FPGA";
159"GPU_3V3IO_RSVD1_ISO_R"CDS_PHYS_NET_NAME"CLK_25M_OSC_MAIN_FPGA";
160"PRSNT_CABLE_GPU_A1_ISO_R_N"CDS_PHYS_NET_NAME"CLK_25M_OSC_MAIN_FPGA";
161"GPU_3V3IO_RSVD1_FFU_ISO_R"CDS_PHYS_NET_NAME"CLK_25M_OSC_MAIN_FPGA";
%"LCMXO3LF9400C5BG484C"
"2","(-2000,2525)","0","pure_quanta","I1";
;
PART_NUMBER"AJ094000T08"
PART_TYPE"SMLF"
VALUE"LCMXO3LF-9400C-5BG484C"
MATERIAL"IC"
$LOCATION"U249"
CDS_LMAN_SYM_OUTLINE"-725,1375,725,-1375"
NEEDS_NO_SIZE"TRUE"
CDS_LIB"pure_quanta"
CDS_LOCATION"U249"
$SEC"2"
CDS_SEC"2";
"PB21D"
$PN"Y10"11;
"PB21C"
$PN"Y9"15;
"PB46D"
$PN"T16"125;
"PB46C"
$PN"V17"128;
"PB44D"
$PN"W18"103;
"PB44C"
$PN"Y19"113;
"PB43D"
$PN"U16"116;
"PB43C"
$PN"T15"120;
"PB41D"
$PN"W17"117;
"PB41C"
$PN"Y18"118;
"PB41B"
$PN"AA18"115;
"PB41A"
$PN"AB18"114;
"PB40D"
$PN"V16"95;
"PB40C"
$PN"Y17"92;
"PB40B"
$PN"AA17"100;
"PB40A"
$PN"AB17"91;
"PB38D"
$PN"U15"93;
"PB38C"
$PN"V15"90;
"PB38B"
$PN"AA16"60;
"PB38A"
$PN"AB16"55;
"PB35D"
$PN"W15"89;
"PB35C"
$PN"Y15"104;
"PB32D"
$PN"V14"35;
"PB32C"
$PN"U14"54;
"PB32B"
$PN"T14"39;
"PB32A"
$PN"T13"40;
"PB33D"
$PN"W14"87;
"PB33C"
$PN"Y14"86;
"PB30D"
$PN"W13"42;
"PB30C"
$PN"Y13"41;
"PB29D"
$PN"U13"88;
"PB29C"
$PN"V13"45;
"PB27D"
$PN"V12"155;
"PB27C"
$PN"U12"156;
"PB27B"
$PN"T12"159;
"PB27A"
$PN"Y12"160;
"PB22D"
$PN"U11"141;
"PB22C"
$PN"T11"142;
"PB19D"
$PN"U10"14;
"PB19C"
$PN"T10"7;
"PB19B"
$PN"AB9"8;
"PB19A"
$PN"AA9"9;
"PB18D"
$PN"W9"111;
"PB18C"
$PN"Y8"61;
"PB16D"
$PN"W8"66;
"PB16C"
$PN"V9"65;
"PB13B"
$PN"AB7"70;
"PB13A"
$PN"AA7"63;
"PB11D"
$PN"V7"62;
"PB11C"
$PN"W6"71;
"PB11B"
$PN"AB6"72;
"PB11A"
$PN"AA6"59;
"PB35B"
$PN"AA15"106;
"PB35A"
$PN"AB15"105;
"PB46B||SI||SISPI"
$PN"AA21"112;
"PB46A||SN"
$PN"AB21"127;
"PB44B"
$PN"AA20"94;
"PB44A"
$PN"AB20"102;
"PB43B"
$PN"AA19"122;
"PB43A"
$PN"AB19"121;
"PB33B"
$PN"AA14"85;
"PB33A"
$PN"AB14"38;
"PB30B"
$PN"AA13"44;
"PB30A"
$PN"AB13"43;
"PB29B||PCLKC2_1"
$PN"AA12"46;
"PB29A||PCLKT2_1"
$PN"AB12"47;
"PB24D"
$PN"Y11"158;
"PB24C"
$PN"V11"157;
"PB24B"
$PN"AB11"144;
"PB24A"
$PN"AA11"27;
"PB22B||PCLKC2_0"
$PN"AB10"143;
"PB22A||PCLKT2_0"
$PN"AA10"10;
"PB21B"
$PN"W10"12;
"PB21A"
$PN"V10"13;
"PB18B"
$PN"AB8"68;
"PB18A"
$PN"AA8"67;
"PB16B||SO||SPISO"
$PN"U9"69;
"PB16A||MCLK||CCLK"
$PN"T9"64;
"PB13D"
$PN"U8"36;
"PB13C"
$PN"V8"37;
"PB10D"
$PN"Y6"73;
"PB10C"
$PN"Y5"58;
"PB10B"
$PN"AB5"84;
"PB10A"
$PN"AA5"83;
"PB8B"
$PN"AB4"81;
"PB8A"
$PN"AA4"74;
"PB8D"
$PN"T8"52;
"PB8C"
$PN"U7"82;
"PB7D"
$PN"W5"80;
"PB7C"
$PN"Y4"79;
"PB7B"
$PN"AB3"78;
"PB7A||CSSPIN"
$PN"AA3"57;
"PB5D"
$PN"U6"77;
"PB5C"
$PN"V6"76;
"PB5B"
$PN"AB2"75;
"PB5A"
$PN"AA2"49;
%"Q_RES"
"1","(-4550,-300)","0","pure_quanta","I103";
;
PART_NUMBER"CS03322FB03"
TOLERANCE"1%"
VALUE"33.2"
MATERIAL"CHIP"
$LOCATION"R4148"
WATTAGE"1/16W"
PACK_TYPE"0402LF"
CDS_LIB"pure_quanta"
CDS_LOCATION"R4148"
$SEC"1"
CDS_SEC"1";
"B"
$PN"2"152;
"A"
$PN"1"139;
%"Q_RES"
"1","(-4550,-125)","0","pure_quanta","I104";
;
PART_NUMBER"CS03322FB03"
VALUE"33.2"
TOLERANCE"1%"
MATERIAL"CHIP"
$LOCATION"R4147"
CDS_LIB"pure_quanta"
PACK_TYPE"0402LF"
WATTAGE"1/16W"
CDS_LOCATION"R4147"
$SEC"1"
CDS_SEC"1";
"B"
$PN"2"145;
"A"
$PN"1"135;
%"Q_RES"
"1","(-4550,-475)","0","pure_quanta","I114";
;
PART_NUMBER"CS03322FB03"
MATERIAL"CHIP"
VALUE"33.2"
TOLERANCE"1%"
$LOCATION"R4157"
CDS_LIB"pure_quanta"
PACK_TYPE"0402LF"
WATTAGE"1/16W"
CDS_LOCATION"R4157"
$SEC"1"
CDS_SEC"1";
"B"
$PN"2"154;
"A"
$PN"1"140;
%"Q_RES"
"1","(-4550,-600)","0","pure_quanta","I120";
;
PART_NUMBER"CS03322FB03"
TOLERANCE"1%"
VALUE"33.2"
MATERIAL"CHIP"
$LOCATION"R4170"
WATTAGE"1/16W"
PACK_TYPE"0402LF"
CDS_LIB"pure_quanta"
CDS_LOCATION"R4170"
$SEC"1"
CDS_SEC"1";
"B"
$PN"2"151;
"A"
$PN"1"138;
%"Q_RES"
"1","(-4550,-775)","0","pure_quanta","I121";
;
PART_NUMBER"CS03322FB03"
TOLERANCE"1%"
VALUE"33.2"
MATERIAL"CHIP"
$LOCATION"R4171"
CDS_LIB"pure_quanta"
PACK_TYPE"0402LF"
WATTAGE"1/16W"
CDS_LOCATION"R4171"
$SEC"1"
CDS_SEC"1";
"B"
$PN"2"153;
"A"
$PN"1"137;
%"Q_RES"
"1","(-4550,-950)","0","pure_quanta","I122";
;
PART_NUMBER"CS03322FB03"
TOLERANCE"1%"
MATERIAL"CHIP"
VALUE"33.2"
$LOCATION"R4172"
WATTAGE"1/16W"
PACK_TYPE"0402LF"
CDS_LIB"pure_quanta"
CDS_LOCATION"R4172"
$SEC"1"
CDS_SEC"1";
"B"
$PN"2"24;
"A"
$PN"1"136;
%"Q_RES"
"1","(-575,875)","0","pure_quanta","I134";
;
PART_NUMBER"CS03322FB03"
VALUE"33.2"
TOLERANCE"1%"
MATERIAL"CHIP"
$LOCATION"R4174"
CDS_LIB"pure_quanta"
PACK_TYPE"0402LF"
WATTAGE"1/16W"
CDS_LOCATION"R4174"
$SEC"1"
CDS_SEC"1";
"B"
$PN"2"109;
"A"
$PN"1"126;
%"Q_RES"
"1","(-575,700)","0","pure_quanta","I135";
;
PART_NUMBER"CS03322FB03"
VALUE"33.2"
MATERIAL"CHIP"
TOLERANCE"1%"
$LOCATION"R4175"
WATTAGE"1/16W"
PACK_TYPE"0402LF"
CDS_LIB"pure_quanta"
CDS_LOCATION"R4175"
$SEC"1"
CDS_SEC"1";
"B"
$PN"2"101;
"A"
$PN"1"126;
%"Q_RES"
"1","(-575,525)","0","pure_quanta","I143";
;
PART_NUMBER"CS03322FB03"
VALUE"33.2"
MATERIAL"CHIP"
TOLERANCE"1%"
$LOCATION"R4556"
CDS_LIB"pure_quanta"
WATTAGE"1/16W"
PACK_TYPE"0402LF"
CDS_LOCATION"R4556"
$SEC"1"
CDS_SEC"1";
"B"
$PN"2"108;
"A"
$PN"1"119;
%"Q_RES"
"1","(-575,350)","0","pure_quanta","I145";
;
PART_NUMBER"CS03322FB03"
VALUE"33.2"
MATERIAL"CHIP"
TOLERANCE"1%"
$LOCATION"R4557"
CDS_LIB"pure_quanta"
WATTAGE"1/16W"
PACK_TYPE"0402LF"
CDS_LOCATION"R4557"
$SEC"1"
CDS_SEC"1";
"B"
$PN"2"107;
"A"
$PN"1"56;
%"Q_RES"
"1","(-575,175)","0","pure_quanta","I150";
;
PART_NUMBER"CS03322FB03"
VALUE"33.2"
TOLERANCE"1%"
MATERIAL"CHIP"
$LOCATION"R4558"
WATTAGE"1/16W"
PACK_TYPE"0402LF"
CDS_LIB"pure_quanta"
CDS_LOCATION"R4558"
$SEC"1"
CDS_SEC"1";
"B"
$PN"2"29;
"A"
$PN"1"150;
%"Q_RES"
"1","(-600,-125)","0","pure_quanta","I158";
;
PART_NUMBER"CS03322FB03"
VALUE"33.2"
MATERIAL"CHIP"
TOLERANCE"1%"
$LOCATION"R4563"
CDS_LIB"pure_quanta"
WATTAGE"1/16W"
PACK_TYPE"0402LF"
CDS_LOCATION"R4563"
$SEC"1"
CDS_SEC"1";
"B"
$PN"2"28;
"A"
$PN"1"129;
%"Q_RES"
"1","(-575,-450)","0","pure_quanta","I164";
;
PART_NUMBER"CS00002JB13"
VALUE"0"
TOLERANCE"5%"
MATERIAL"CHIP"
$LOCATION"R3045"
WATTAGE"1/16W"
PACK_TYPE"0402LF"
CDS_LIB"pure_quanta"
CDS_LOCATION"R3045"
$SEC"1"
CDS_SEC"1";
"B"
$PN"2"96;
"A"
$PN"1"30;
%"Q_RES"
"1","(-575,-675)","0","pure_quanta","I165";
;
PART_NUMBER"CS00002JB13"
TOLERANCE"5%"
MATERIAL"CHIP"
VALUE"0"
$LOCATION"R3046"
CDS_LIB"pure_quanta"
PACK_TYPE"0402LF"
WATTAGE"1/16W"
CDS_LOCATION"R3046"
$SEC"1"
CDS_SEC"1";
"B"
$PN"2"48;
"A"
$PN"1"31;
%"Q_RES"
"1","(-575,-850)","0","pure_quanta","I169";
;
PART_NUMBER"CS00002JB13"
WATTAGE"1/16W"
MATERIAL"CHIP"
TOLERANCE"5%"
VALUE"0"
$LOCATION"R700"
PACK_TYPE"0402LF"
CDS_LIB"pure_quanta"
CDS_LOCATION"R700"
$SEC"1"
CDS_SEC"1";
"B"
$PN"2"97;
"A"
$PN"1"32;
%"Q_RES"
"1","(-575,-1025)","0","pure_quanta","I170";
;
PART_NUMBER"CS00002JB13"
PACK_TYPE"0402LF"
MATERIAL"CHIP"
WATTAGE"1/16W"
TOLERANCE"5%"
VALUE"0"
$LOCATION"R1944"
CDS_LIB"pure_quanta"
CDS_LOCATION"R1944"
$SEC"1"
CDS_SEC"1";
"B"
$PN"2"98;
"A"
$PN"1"25;
%"Q_RES"
"1","(-575,-1225)","0","pure_quanta","I176";
;
PART_NUMBER"CS00002JB13"
MATERIAL"CHIP"
PACK_TYPE"0402LF"
WATTAGE"1/16W"
TOLERANCE"5%"
VALUE"0"
$LOCATION"R3049"
CDS_LIB"pure_quanta"
CDS_LOCATION"R3049"
$SEC"1"
CDS_SEC"1";
"B"
$PN"2"99;
"A"
$PN"1"26;
%"Q_RES"
"1","(-575,-1400)","0","pure_quanta","I177";
;
PART_NUMBER"CS00002JB13"
MATERIAL"CHIP"
VALUE"0"
TOLERANCE"5%"
$LOCATION"R2155"
CDS_LIB"pure_quanta"
PACK_TYPE"0402LF"
WATTAGE"1/16W"
CDS_LOCATION"R2155"
$SEC"1"
CDS_SEC"1";
"B"
$PN"2"124;
"A"
$PN"1"33;
%"Q_RES"
"1","(-575,-1575)","0","pure_quanta","I178";
;
PART_NUMBER"CS00002JB13"
VALUE"0"
MATERIAL"CHIP"
TOLERANCE"5%"
$LOCATION"R2792"
WATTAGE"1/16W"
PACK_TYPE"0402LF"
CDS_LIB"pure_quanta"
CDS_LOCATION"R2792"
$SEC"1"
CDS_SEC"1";
"B"
$PN"2"110;
"A"
$PN"1"23;
%"Q_RES"
"1","(-4550,-1325)","0","pure_quanta","I183";
;
PART_NUMBER"CS00002JB13"
MATERIAL"CHIP"
VALUE"0"
TOLERANCE"5%"
$LOCATION"R2347"
PACK_TYPE"0402LF"
WATTAGE"1/16W"
CDS_LIB"pure_quanta"
CDS_LOCATION"R2347"
$SEC"1"
CDS_SEC"1";
"B"
$PN"2"21;
"A"
$PN"1"34;
%"Q_RES"
"1","(-4550,-1525)","0","pure_quanta","I184";
;
PART_NUMBER"CS00002JB13"
VALUE"0"
TOLERANCE"5%"
MATERIAL"CHIP"
$LOCATION"R2348"
CDS_LIB"pure_quanta"
WATTAGE"1/16W"
PACK_TYPE"0402LF"
CDS_LOCATION"R2348"
$SEC"1"
CDS_SEC"1";
"B"
$PN"2"20;
"A"
$PN"1"18;
%"CONN3_210HP1030BR1"
"1","(-5050,3575)","0","pure_quanta","I187";
;
PART_NUMBER"DFHD03MS213"
VALUE"CONN3_210-HP1-030BR1"
PART_TYPE"THLF"
MATERIAL"IO"
$LOCATION"JP15"
CDS_LIB"pure_quanta"
CDS_LMAN_SYM_OUTLINE"-50,100,50,-100"
NEEDS_NO_SIZE"TRUE"
CDS_LOCATION"JP15"
$SEC"1"
CDS_SEC"1";
"1"
$PN"1"50;
"2"
$PN"2"51;
"3"
$PN"3"53;
%"UNIVERSAL_POWER"
"1","(-6000,4075)","0","logical_power","I188";
;
HDL_POWER"P3V3_AUX"
CDS_LIB"logical_power";
"A"2;
%"UNIVERSAL_GND"
"1","(-6000,3100)","0","logical_power","I189";
;
CDS_LIB"logical_power"
HDL_POWER"GND";
"A"5;
%"Q_RES"
"2","(-6000,3325)","0","pure_quanta","I190";
;
PART_NUMBER"CS31002FB08"
MATERIAL"CHIP"
WATTAGE"1/16W"
VALUE"10K"
TOLERANCE"1%"
PACK_TYPE"0402LF"
$LOCATION"R1495"
CDS_LIB"pure_quanta"
CDS_LOCATION"R1495"
$SEC"1"
CDS_SEC"1";
"A"
$PN"1"53;
"B"
$PN"2"5;
%"Q_RES"
"2","(-6000,3875)","0","pure_quanta","I191";
;
PART_NUMBER"CS21002FB06"
TOLERANCE"1%"
PACK_TYPE"0402LF"
VALUE"1K"
WATTAGE"1/16W"
MATERIAL"CHIP"
$LOCATION"R1493"
CDS_LIB"pure_quanta"
CDS_LOCATION"R1493"
$SEC"1"
CDS_SEC"1";
"A"
$PN"1"2;
"B"
$PN"2"50;
%"UNIVERSAL_POWER"
"1","(975,3900)","0","logical_power","I2";
;
HDL_POWER"P3V3_AUX"
CDS_LIB"logical_power";
"A"1;
%"Q_RES"
"1","(-4550,-1775)","0","pure_quanta","I213";
;
PART_NUMBER"CS03322FB03"
VALUE"33.2"
MATERIAL"CHIP"
TOLERANCE"1%"
$LOCATION"R4723"
PACK_TYPE"0402LF"
WATTAGE"1/16W"
CDS_LIB"pure_quanta"
CDS_LOCATION"R4723"
$SEC"1"
CDS_SEC"1";
"B"
$PN"2"19;
"A"
$PN"1"22;
%"Q_RES"
"1","(-4550,700)","0","pure_quanta","I217";
;
PART_NUMBER"CS03322FB03"
MATERIAL"CHIP"
VALUE"33.2"
TOLERANCE"1%"
LOCATION"R4057"
WATTAGE"1/16W"
PACK_TYPE"0402LF"
CDS_LIB"pure_quanta"
$SEC"1"
CDS_SEC"1";
"B"
$PN"2"148;
"A"
$PN"1"132;
%"Q_RES"
"2","(975,3650)","0","pure_quanta","I3";
;
PART_NUMBER"CS31002FB08"
PACK_TYPE"0402LF"
MATERIAL"EMPTY"
WATTAGE"1/16W"
TOLERANCE"1%"
VALUE"10K"
$LOCATION"R1465"
CDS_LIB"pure_quanta"
CDS_LOCATION"R1465"
$SEC"1"
CDS_SEC"1";
"A"
$PN"1"1;
"B"
$PN"2"88;
%"Q_RES"
"1","(950,2375)","0","pure_quanta","I38";
;
PART_NUMBER"CS04992FB07"
VALUE"49.9"
MATERIAL"CHIP"
TOLERANCE"1%"
PACK_TYPE"0402LF"
WATTAGE"1/16W"
$LOCATION"R1710"
CDS_LIB"pure_quanta"
CDS_LOCATION"R1710"
$SEC"1"
CDS_SEC"1";
"B"
$PN"2"123;
"A"
$PN"1"122;
%"Q_CAP"
"1","(775,2050)","2","pure_quanta","I39";
;
PART_NUMBER"CH4104K1B00"
VALUE"0.1UF"
MATERIAL"X7R"
TOLERANCE"10%"
VOLTAGE"25V"
PACK_TYPE"0402"
$LOCATION"C1325"
CDS_LIB"pure_quanta"
CDS_LOCATION"C1325"
$SEC"1"
CDS_SEC"1";
"B"
$PN"2"6;
"A"
$PN"1"122;
%"UNIVERSAL_POWER"
"1","(1775,2750)","0","logical_power","I4";
;
HDL_POWER"P3V3_AUX"
CDS_LIB"logical_power";
"A"3;
%"UNIVERSAL_GND"
"1","(775,1775)","0","logical_power","I40";
;
HDL_POWER"GND"
CDS_LIB"logical_power";
"A"6;
%"Q_RES"
"2","(1775,2500)","0","pure_quanta","I5";
;
PART_NUMBER"CS31002FB08"
TOLERANCE"1%"
VALUE"10K"
WATTAGE"1/16W"
MATERIAL"CHIP"
PACK_TYPE"0402LF"
$LOCATION"R1106"
CDS_LIB"pure_quanta"
CDS_LOCATION"R1106"
$SEC"1"
CDS_SEC"1";
"A"
$PN"1"3;
"B"
$PN"2"123;
%"Q_RES"
"1","(-4550,875)","0","pure_quanta","I80";
;
PART_NUMBER"CS00002JB13"
MATERIAL"CHIP"
TOLERANCE"5%"
VALUE"0"
$LOCATION"R4056"
CDS_LIB"pure_quanta"
WATTAGE"1/16W"
PACK_TYPE"0402LF"
CDS_LOCATION"R4056"
$SEC"1"
CDS_SEC"1";
"B"
$PN"2"149;
"A"
$PN"1"16;
%"Q_RES"
"2","(1775,1825)","0","pure_quanta","I86";
;
PART_NUMBER"CS31002FB08"
VALUE"10K"
PACK_TYPE"0402LF"
MATERIAL"CHIP"
TOLERANCE"1%"
WATTAGE"1/16W"
$LOCATION"R4086"
CDS_LIB"pure_quanta"
CDS_LOCATION"R4086"
$SEC"1"
CDS_SEC"1";
"A"
$PN"1"4;
"B"
$PN"2"127;
%"UNIVERSAL_POWER"
"1","(1775,2050)","0","logical_power","I87";
;
HDL_POWER"P3V3_AUX_FPGA_VCCIO2"
CDS_LIB"logical_power";
"A"4;
%"Q_RES"
"1","(-4550,525)","0","pure_quanta","I89";
;
PART_NUMBER"CS03322FB03"
TOLERANCE"1%"
VALUE"33.2"
MATERIAL"CHIP"
$LOCATION"R4143"
CDS_LIB"pure_quanta"
WATTAGE"1/16W"
PACK_TYPE"0402LF"
CDS_LOCATION"R4143"
$SEC"1"
CDS_SEC"1";
"B"
$PN"2"17;
"A"
$PN"1"131;
%"Q_RES"
"1","(-4550,350)","0","pure_quanta","I93";
;
PART_NUMBER"CS03322FB03"
TOLERANCE"1%"
VALUE"33.2"
MATERIAL"CHIP"
$LOCATION"R4144"
CDS_LIB"pure_quanta"
PACK_TYPE"0402LF"
WATTAGE"1/16W"
CDS_LOCATION"R4144"
$SEC"1"
CDS_SEC"1";
"B"
$PN"2"161;
"A"
$PN"1"130;
%"Q_RES"
"1","(-4550,200)","0","pure_quanta","I97";
;
PART_NUMBER"CS03322FB03"
VALUE"33.2"
TOLERANCE"1%"
MATERIAL"CHIP"
$LOCATION"R4145"
WATTAGE"1/16W"
PACK_TYPE"0402LF"
CDS_LIB"pure_quanta"
CDS_LOCATION"R4145"
$SEC"1"
CDS_SEC"1";
"B"
$PN"2"147;
"A"
$PN"1"134;
%"Q_RES"
"1","(-4550,25)","0","pure_quanta","I98";
;
PART_NUMBER"CS03322FB03"
VALUE"33.2"
TOLERANCE"1%"
MATERIAL"CHIP"
$LOCATION"R4146"
WATTAGE"1/16W"
PACK_TYPE"0402LF"
CDS_LIB"pure_quanta"
CDS_LOCATION"R4146"
$SEC"1"
CDS_SEC"1";
"B"
$PN"2"146;
"A"
$PN"1"133;
END.
